# SCM (Grand Teton) — schematic netlist excerpt (pin names and nets, part order shuffled) for the footprints in the layout excerpt that follows; sources: Cadence DE-HDL packaged netlist, KiCad conversion of 12092022_DA0F0TMDCD0_F0T_Management_Board_D_brd_V3_OCP.brd

PC264  Q_CAP  0.22UF 16V 10% X7R  pkg 0402  page 56 : A = SW_P1V0_AUX_BST ; B = SW_P1V0_AUX_SW
R441  Q_RES  49.9 1% EMPTY  pkg 0402LF  page 15 : A = USB_HOST_BMC_A_DN ; B = GND

(kicad_pcb
	(version 20260206)
	(generator "pcbnew")
	(generator_version "10.0")
	(general
		(thickness 1.6)
		(legacy_teardrops no)
	)
	(paper "A4")
	(title_block
		(title "12092022_DA0F0TMDCD0_F0T_Management_Board_D_brd_V3_OCP.brd")
		(comment 1 "Grand Teton / footprints 712-713 of 1440")
	)
	(layers
		(0 "F.Cu" signal "TOP")
		(4 "In1.Cu" signal "GND")
		(6 "In2.Cu" signal "IN1")
		(8 "In3.Cu" signal "GND1")
		(10 "In4.Cu" signal "IN2")
		(12 "In5.Cu" signal "VCC")
		(14 "In6.Cu" signal "VCC1")
		(16 "In7.Cu" signal "IN3")
		(18 "In8.Cu" signal "GND2")
		(20 "In9.Cu" signal "IN4")
		(22 "In10.Cu" signal "GND3")
		(2 "B.Cu" signal "BOTTOM")
		(9 "F.Adhes" user "F.Adhesive")
		(11 "B.Adhes" user "B.Adhesive")
		(13 "F.Paste" user "Package Geometry/Pastemask Top")
		(15 "B.Paste" user "Package Geometry/Pastemask Bottom")
		(5 "F.SilkS" user "Ref Des/Silkscreen Top")
		(7 "B.SilkS" user "Ref Des/Silkscreen Bottom")
		(1 "F.Mask" user "Board Geometry/Soldermask Top")
		(3 "B.Mask" user "Board Geometry/Soldermask Bottom")
		(17 "Dwgs.User" user "User.Drawings")
		(19 "Cmts.User" user "User.Comments")
		(21 "Eco1.User" user "User.Eco1")
		(23 "Eco2.User" user "User.Eco2")
		(25 "Edge.Cuts" user "Board Geometry/Outline")
		(27 "Margin" user)
		(31 "F.CrtYd" user "Package Geometry/Place Bound Top")
		(29 "B.CrtYd" user "Package Geometry/Place Bound Bottom")
		(35 "F.Fab" user "Ref Des/Assembly Top")
		(33 "B.Fab" user "Ref Des/Assembly Bottom")
	)
	(footprint ""
		(layer "F.Cu")
		(at 20.209764 -30.026864 180)
		(property "Reference" "PC264"
			(at 0 0 180)
			(layer "F.SilkS")
			(hide yes)
			(effects
				(font
					(size 1.27 1.27)
				)
			)
		)
		(property "Value" ""
			(at 0 0 180)
			(layer "F.Fab")
			(effects
				(font
					(size 1.27 1.27)
				)
			)
		)
		(duplicate_pad_numbers_are_jumpers no)
		(fp_line
			(start 0.7874 0.4064)
			(end -0.7874 0.4064)
			(stroke
				(width 0.1524)
				(type default)
			)
			(layer "F.SilkS")
		)
		(fp_line
			(start 0.7874 -0.4064)
			(end 0.7874 0.4064)
			(stroke
				(width 0.1524)
				(type default)
			)
			(layer "F.SilkS")
		)
		(fp_line
			(start -0.7874 0.4064)
			(end -0.7874 -0.4064)
			(stroke
				(width 0.1524)
				(type default)
			)
			(layer "F.SilkS")
		)
		(fp_line
			(start -0.7874 -0.4064)
			(end 0.7874 -0.4064)
			(stroke
				(width 0.1524)
				(type default)
			)
			(layer "F.SilkS")
		)
		(fp_line
			(start 0.67945 0.3048)
			(end 0.120396 0.3048)
			(stroke
				(width 0.1)
				(type default)
			)
			(layer "F.Fab")
		)
		(fp_line
			(start 0.67945 -0.3048)
			(end 0.67945 0.3048)
			(stroke
				(width 0.1)
				(type default)
			)
			(layer "F.Fab")
		)
		(fp_line
			(start 0.12065 -0.2794)
			(end 0.12065 -0.3048)
			(stroke
				(width 0.1)
				(type default)
			)
			(layer "F.Fab")
		)
		(fp_line
			(start 0.12065 -0.3048)
			(end 0.67945 -0.3048)
			(stroke
				(width 0.1)
				(type default)
			)
			(layer "F.Fab")
		)
		(fp_line
			(start 0.120396 0.3048)
			(end 0.120396 0.2794)
			(stroke
				(width 0.1)
				(type default)
			)
			(layer "F.Fab")
		)
		(fp_line
			(start 0.120396 0.2794)
			(end -0.12065 0.2794)
			(stroke
				(width 0.1)
				(type default)
			)
			(layer "F.Fab")
		)
		(fp_line
			(start -0.12065 0.3048)
			(end -0.67945 0.3048)
			(stroke
				(width 0.1)
				(type default)
			)
			(layer "F.Fab")
		)
		(fp_line
			(start -0.12065 0.2794)
			(end -0.12065 0.3048)
			(stroke
				(width 0.1)
				(type default)
			)
			(layer "F.Fab")
		)
		(fp_line
			(start -0.12065 -0.2794)
			(end 0.12065 -0.2794)
			(stroke
				(width 0.1)
				(type default)
			)
			(layer "F.Fab")
		)
		(fp_line
			(start -0.12065 -0.305054)
			(end -0.12065 -0.2794)
			(stroke
				(width 0.1)
				(type default)
			)
			(layer "F.Fab")
		)
		(fp_line
			(start -0.67945 0.3048)
			(end -0.67945 -0.305054)
			(stroke
				(width 0.1)
				(type default)
			)
			(layer "F.Fab")
		)
		(fp_line
			(start -0.67945 -0.305054)
			(end -0.12065 -0.305054)
			(stroke
				(width 0.1)
				(type default)
			)
			(layer "F.Fab")
		)
		(pad "1" smd circle
			(at -0.40005 0 180)
			(size 0 0)
			(layers "F.Cu" "F.Mask" "F.Paste")
			(net "SW_P1V0_AUX_BST")
		)
		(pad "2" smd circle
			(at 0.40005 0 180)
			(size 0 0)
			(layers "F.Cu" "F.Mask" "F.Paste")
			(net "SW_P1V0_AUX_SW")
		)
	)
	(footprint ""
		(layer "F.Cu")
		(at 66.167 -28.0162)
		(property "Reference" "R441"
			(at 0 0 0)
			(layer "F.SilkS")
			(hide yes)
			(effects
				(font
					(size 1.27 1.27)
				)
			)
		)
		(property "Value" ""
			(at 0 0 0)
			(layer "F.Fab")
			(effects
				(font
					(size 1.27 1.27)
				)
			)
		)
		(duplicate_pad_numbers_are_jumpers no)
		(fp_line
			(start -0.5588 -0.4064)
			(end 0.7874 -0.4064)
			(stroke
				(width 0.1524)
				(type default)
			)
			(layer "F.SilkS")
		)
		(fp_line
			(start 0.7874 -0.4064)
			(end 0.7874 0.4064)
			(stroke
				(width 0.1524)
				(type default)
			)
			(layer "F.SilkS")
		)
		(fp_line
			(start 0.7874 0.4064)
			(end -0.4318 0.4064)
			(stroke
				(width 0.1524)
				(type default)
			)
			(layer "F.SilkS")
		)
		(fp_line
			(start -0.67945 -0.305054)
			(end -0.12065 -0.305054)
			(stroke
				(width 0.1)
				(type default)
			)
			(layer "F.Fab")
		)
		(fp_line
			(start -0.67945 0.3048)
			(end -0.67945 -0.305054)
			(stroke
				(width 0.1)
				(type default)
			)
			(layer "F.Fab")
		)
		(fp_line
			(start -0.12065 -0.305054)
			(end -0.12065 -0.2794)
			(stroke
				(width 0.1)
				(type default)
			)
			(layer "F.Fab")
		)
		(fp_line
			(start -0.12065 -0.2794)
			(end 0.12065 -0.2794)
			(stroke
				(width 0.1)
				(type default)
			)
			(layer "F.Fab")
		)
		(fp_line
			(start -0.12065 0.2794)
			(end -0.12065 0.3048)
			(stroke
				(width 0.1)
				(type default)
			)
			(layer "F.Fab")
		)
		(fp_line
			(start -0.12065 0.3048)
			(end -0.67945 0.3048)
			(stroke
				(width 0.1)
				(type default)
			)
			(layer "F.Fab")
		)
		(fp_line
			(start 0.120396 0.2794)
			(end -0.12065 0.2794)
			(stroke
				(width 0.1)
				(type default)
			)
			(layer "F.Fab")
		)
		(fp_line
			(start 0.120396 0.3048)
			(end 0.120396 0.2794)
			(stroke
				(width 0.1)
				(type default)
			)
			(layer "F.Fab")
		)
		(fp_line
			(start 0.12065 -0.3048)
			(end 0.67945 -0.3048)
			(stroke
				(width 0.1)
				(type default)
			)
			(layer "F.Fab")
		)
		(fp_line
			(start 0.12065 -0.2794)
			(end 0.12065 -0.3048)
			(stroke
				(width 0.1)
				(type default)
			)
			(layer "F.Fab")
		)
		(fp_line
			(start 0.67945 -0.3048)
			(end 0.67945 0.3048)
			(stroke
				(width 0.1)
				(type default)
			)
			(layer "F.Fab")
		)
		(fp_line
			(start 0.67945 0.3048)
			(end 0.120396 0.3048)
			(stroke
				(width 0.1)
				(type default)
			)
			(layer "F.Fab")
		)
		(pad "1" smd circle
			(at -0.40005 0)
			(size 0 0)
			(layers "F.Cu" "F.Mask" "F.Paste")
			(net "USB_HOST_BMC_A_DN")
		)
		(pad "2" smd circle
			(at 0.40005 0)
			(size 0 0)
			(layers "F.Cu" "F.Mask" "F.Paste")
			(net "GND")
		)
	)
)
